# SCM (Grand Teton) — schematic netlist excerpt (pin names and nets, part order shuffled) for the footprints in the layout excerpt that follows; sources: Cadence DE-HDL packaged netlist, KiCad conversion of 12092022_DA0F0TMDCD0_F0T_Management_Board_D_brd_V3_OCP.brd

R306  Q_RES  10K 1% CHIP  pkg 0402LF  page 49 : A = BEEP_LED ; B = GND
C93  Q_CAP  0.1UF 25V 10% X7R  pkg 0402  page 16 : A = P1V8_AUX ; B = GND

(kicad_pcb
	(version 20260206)
	(generator "pcbnew")
	(generator_version "10.0")
	(general
		(thickness 1.6)
		(legacy_teardrops no)
	)
	(paper "A4")
	(title_block
		(title "12092022_DA0F0TMDCD0_F0T_Management_Board_D_brd_V3_OCP.brd")
		(comment 1 "Grand Teton / footprints 947-948 of 1440")
	)
	(layers
		(0 "F.Cu" signal "TOP")
		(4 "In1.Cu" signal "GND")
		(6 "In2.Cu" signal "IN1")
		(8 "In3.Cu" signal "GND1")
		(10 "In4.Cu" signal "IN2")
		(12 "In5.Cu" signal "VCC")
		(14 "In6.Cu" signal "VCC1")
		(16 "In7.Cu" signal "IN3")
		(18 "In8.Cu" signal "GND2")
		(20 "In9.Cu" signal "IN4")
		(22 "In10.Cu" signal "GND3")
		(2 "B.Cu" signal "BOTTOM")
		(9 "F.Adhes" user "F.Adhesive")
		(11 "B.Adhes" user "B.Adhesive")
		(13 "F.Paste" user "Package Geometry/Pastemask Top")
		(15 "B.Paste" user "Package Geometry/Pastemask Bottom")
		(5 "F.SilkS" user "Ref Des/Silkscreen Top")
		(7 "B.SilkS" user "Ref Des/Silkscreen Bottom")
		(1 "F.Mask" user "Board Geometry/Soldermask Top")
		(3 "B.Mask" user "Board Geometry/Soldermask Bottom")
		(17 "Dwgs.User" user "User.Drawings")
		(19 "Cmts.User" user "User.Comments")
		(21 "Eco1.User" user "User.Eco1")
		(23 "Eco2.User" user "User.Eco2")
		(25 "Edge.Cuts" user "Board Geometry/Outline")
		(27 "Margin" user)
		(31 "F.CrtYd" user "Package Geometry/Place Bound Top")
		(29 "B.CrtYd" user "Package Geometry/Place Bound Bottom")
		(35 "F.Fab" user "Ref Des/Assembly Top")
		(33 "B.Fab" user "Ref Des/Assembly Bottom")
	)
	(footprint ""
		(layer "B.Cu")
		(at 12.192 -24.384 -90)
		(property "Reference" "R306"
			(at 0 0 90)
			(layer "B.SilkS")
			(hide yes)
			(effects
				(font
					(size 1.27 1.27)
				)
				(justify mirror)
			)
		)
		(property "Value" ""
			(at 0 0 90)
			(layer "B.Fab")
			(effects
				(font
					(size 1.27 1.27)
				)
				(justify mirror)
			)
		)
		(duplicate_pad_numbers_are_jumpers no)
		(fp_line
			(start -0.7874 0.4064)
			(end 0.7874 0.4064)
			(stroke
				(width 0.1524)
				(type default)
			)
			(layer "B.SilkS")
		)
		(fp_line
			(start 0.7874 0.4064)
			(end 0.7874 -0.4064)
			(stroke
				(width 0.1524)
				(type default)
			)
			(layer "B.SilkS")
		)
		(fp_line
			(start -0.7874 -0.4064)
			(end -0.7874 0.4064)
			(stroke
				(width 0.1524)
				(type default)
			)
			(layer "B.SilkS")
		)
		(fp_line
			(start 0.7874 -0.4064)
			(end -0.7874 -0.4064)
			(stroke
				(width 0.1524)
				(type default)
			)
			(layer "B.SilkS")
		)
		(fp_line
			(start -0.67945 0.3048)
			(end -0.120396 0.3048)
			(stroke
				(width 0.1)
				(type default)
			)
			(layer "B.Fab")
		)
		(fp_line
			(start -0.120396 0.3048)
			(end -0.120396 0.2794)
			(stroke
				(width 0.1)
				(type default)
			)
			(layer "B.Fab")
		)
		(fp_line
			(start 0.12065 0.3048)
			(end 0.67945 0.3048)
			(stroke
				(width 0.1)
				(type default)
			)
			(layer "B.Fab")
		)
		(fp_line
			(start 0.67945 0.3048)
			(end 0.67945 -0.305054)
			(stroke
				(width 0.1)
				(type default)
			)
			(layer "B.Fab")
		)
		(fp_line
			(start -0.120396 0.2794)
			(end 0.12065 0.2794)
			(stroke
				(width 0.1)
				(type default)
			)
			(layer "B.Fab")
		)
		(fp_line
			(start 0.12065 0.2794)
			(end 0.12065 0.3048)
			(stroke
				(width 0.1)
				(type default)
			)
			(layer "B.Fab")
		)
		(fp_line
			(start -0.12065 -0.2794)
			(end -0.12065 -0.3048)
			(stroke
				(width 0.1)
				(type default)
			)
			(layer "B.Fab")
		)
		(fp_line
			(start 0.12065 -0.2794)
			(end -0.12065 -0.2794)
			(stroke
				(width 0.1)
				(type default)
			)
			(layer "B.Fab")
		)
		(fp_line
			(start -0.67945 -0.3048)
			(end -0.67945 0.3048)
			(stroke
				(width 0.1)
				(type default)
			)
			(layer "B.Fab")
		)
		(fp_line
			(start -0.12065 -0.3048)
			(end -0.67945 -0.3048)
			(stroke
				(width 0.1)
				(type default)
			)
			(layer "B.Fab")
		)
		(fp_line
			(start 0.12065 -0.305054)
			(end 0.12065 -0.2794)
			(stroke
				(width 0.1)
				(type default)
			)
			(layer "B.Fab")
		)
		(fp_line
			(start 0.67945 -0.305054)
			(end 0.12065 -0.305054)
			(stroke
				(width 0.1)
				(type default)
			)
			(layer "B.Fab")
		)
		(pad "1" smd circle
			(at 0.40005 0 90)
			(size 0 0)
			(layers "B.Cu" "B.Mask" "B.Paste")
			(net "BEEP_LED")
		)
		(pad "2" smd circle
			(at -0.40005 0 90)
			(size 0 0)
			(layers "B.Cu" "B.Mask" "B.Paste")
			(net "GND")
		)
	)
	(footprint ""
		(layer "B.Cu")
		(at 58.092848 -49.54778 -90)
		(property "Reference" "C93"
			(at 0 0 90)
			(layer "B.SilkS")
			(hide yes)
			(effects
				(font
					(size 1.27 1.27)
				)
				(justify mirror)
			)
		)
		(property "Value" ""
			(at 0 0 90)
			(layer "B.Fab")
			(effects
				(font
					(size 1.27 1.27)
				)
				(justify mirror)
			)
		)
		(duplicate_pad_numbers_are_jumpers no)
		(fp_line
			(start -0.7874 0.4064)
			(end 0.7874 0.4064)
			(stroke
				(width 0.1524)
				(type default)
			)
			(layer "B.SilkS")
		)
		(fp_line
			(start 0.7874 0.4064)
			(end 0.7874 -0.4064)
			(stroke
				(width 0.1524)
				(type default)
			)
			(layer "B.SilkS")
		)
		(fp_line
			(start -0.7874 -0.4064)
			(end -0.7874 0.4064)
			(stroke
				(width 0.1524)
				(type default)
			)
			(layer "B.SilkS")
		)
		(fp_line
			(start 0.7874 -0.4064)
			(end -0.7874 -0.4064)
			(stroke
				(width 0.1524)
				(type default)
			)
			(layer "B.SilkS")
		)
		(fp_line
			(start -0.67945 0.3048)
			(end -0.120396 0.3048)
			(stroke
				(width 0.1)
				(type default)
			)
			(layer "B.Fab")
		)
		(fp_line
			(start -0.120396 0.3048)
			(end -0.120396 0.2794)
			(stroke
				(width 0.1)
				(type default)
			)
			(layer "B.Fab")
		)
		(fp_line
			(start 0.12065 0.3048)
			(end 0.67945 0.3048)
			(stroke
				(width 0.1)
				(type default)
			)
			(layer "B.Fab")
		)
		(fp_line
			(start 0.67945 0.3048)
			(end 0.67945 -0.305054)
			(stroke
				(width 0.1)
				(type default)
			)
			(layer "B.Fab")
		)
		(fp_line
			(start -0.120396 0.2794)
			(end 0.12065 0.2794)
			(stroke
				(width 0.1)
				(type default)
			)
			(layer "B.Fab")
		)
		(fp_line
			(start 0.12065 0.2794)
			(end 0.12065 0.3048)
			(stroke
				(width 0.1)
				(type default)
			)
			(layer "B.Fab")
		)
		(fp_line
			(start -0.12065 -0.2794)
			(end -0.12065 -0.3048)
			(stroke
				(width 0.1)
				(type default)
			)
			(layer "B.Fab")
		)
		(fp_line
			(start 0.12065 -0.2794)
			(end -0.12065 -0.2794)
			(stroke
				(width 0.1)
				(type default)
			)
			(layer "B.Fab")
		)
		(fp_line
			(start -0.67945 -0.3048)
			(end -0.67945 0.3048)
			(stroke
				(width 0.1)
				(type default)
			)
			(layer "B.Fab")
		)
		(fp_line
			(start -0.12065 -0.3048)
			(end -0.67945 -0.3048)
			(stroke
				(width 0.1)
				(type default)
			)
			(layer "B.Fab")
		)
		(fp_line
			(start 0.12065 -0.305054)
			(end 0.12065 -0.2794)
			(stroke
				(width 0.1)
				(type default)
			)
			(layer "B.Fab")
		)
		(fp_line
			(start 0.67945 -0.305054)
			(end 0.12065 -0.305054)
			(stroke
				(width 0.1)
				(type default)
			)
			(layer "B.Fab")
		)
		(pad "1" smd circle
			(at 0.40005 0 90)
			(size 0 0)
			(layers "B.Cu" "B.Mask" "B.Paste")
			(net "P1V8_AUX")
		)
		(pad "2" smd circle
			(at -0.40005 0 90)
			(size 0 0)
			(layers "B.Cu" "B.Mask" "B.Paste")
			(net "GND")
		)
	)
)
